(kicad_pcb
	(version 20241229)
	(generator "pcbnew")
	(generator_version "9.0")
	(general
		(thickness 1.6296)
		(legacy_teardrops no)
	)
	(paper "A3")
	(title_block
		(title "Thunderbolt to 10GbE adapter")
		(date "2026-04-21")
		(rev "1.1.0")
		(company "Antmicro Ltd")
		(comment 1 "www.antmicro.com")
		(comment 9 "footprints 416-420 of 703")
	)
	(layers
		(0 "F.Cu" signal)
		(4 "In1.Cu" signal)
		(6 "In2.Cu" signal)
		(8 "In3.Cu" signal)
		(10 "In4.Cu" signal)
		(12 "In5.Cu" signal)
		(14 "In6.Cu" signal)
		(2 "B.Cu" signal)
		(9 "F.Adhes" user "F.Adhesive")
		(11 "B.Adhes" user "B.Adhesive")
		(13 "F.Paste" user)
		(15 "B.Paste" user)
		(5 "F.SilkS" user "F.Silkscreen")
		(7 "B.SilkS" user "B.Silkscreen")
		(1 "F.Mask" user)
		(3 "B.Mask" user)
		(17 "Dwgs.User" user "User.Drawings")
		(19 "Cmts.User" user "User.Comments")
		(21 "Eco1.User" user "User.Eco1")
		(23 "Eco2.User" user "User.Eco2")
		(25 "Edge.Cuts" user)
		(27 "Margin" user)
		(31 "F.CrtYd" user "F.Courtyard")
		(29 "B.CrtYd" user "B.Courtyard")
		(35 "F.Fab" user)
		(33 "B.Fab" user)
	)
	(footprint "antmicro-footprints:R_0402_1005Metric"
		(layer "B.Cu")
		(at 117.5 91.7 -90)
		(descr "Resistor SMD 0402")
		(tags "resistor SMD 0402")
		(property "Reference" "R72"
			(at 6.3 -0.3 90)
			(layer "B.SilkS")
			(effects
				(font
					(size 0.7 0.7)
					(thickness 0.15)
				)
				(justify left bottom mirror)
			)
		)
		(property "Value" "R_1k_0402"
			(at -1.011843 -1.772047 90)
			(layer "B.Fab")
			(effects
				(font
					(size 0.7 0.7)
					(thickness 0.15)
				)
				(justify left bottom mirror)
			)
		)
		(property "Datasheet" "https://www.bourns.com/docs/product-datasheets/cr.pdf"
			(at 0 0 90)
			(layer "B.Fab")
			(hide yes)
			(effects
				(font
					(size 1.27 1.27)
					(thickness 0.15)
				)
				(justify mirror)
			)
		)
		(property "Description" "SMD Chip Resistor, 1 kohm, ± 1%, 63 mW, 0402 [1005 Metric], Thick Film, General Purpose"
			(at 0 0 90)
			(layer "B.Fab")
			(hide yes)
			(effects
				(font
					(size 1.27 1.27)
					(thickness 0.15)
				)
				(justify mirror)
			)
		)
		(property "MPN" "CR0402-FX-1001GLF"
			(at 0 0 270)
			(unlocked yes)
			(layer "B.Fab")
			(hide yes)
			(effects
				(font
					(size 1 1)
					(thickness 0.15)
				)
				(justify mirror)
			)
		)
		(property "Manufacturer" "Bourns"
			(at 0 0 270)
			(unlocked yes)
			(layer "B.Fab")
			(hide yes)
			(effects
				(font
					(size 1 1)
					(thickness 0.15)
				)
				(justify mirror)
			)
		)
		(property "License" "Apache-2.0"
			(at 0 0 270)
			(unlocked yes)
			(layer "B.Fab")
			(hide yes)
			(effects
				(font
					(size 1 1)
					(thickness 0.15)
				)
				(justify mirror)
			)
		)
		(property "Val" "1k"
			(at 0 0 270)
			(unlocked yes)
			(layer "B.Fab")
			(hide yes)
			(effects
				(font
					(size 1 1)
					(thickness 0.15)
				)
				(justify mirror)
			)
		)
		(property "Tolerance" "1%"
			(at 0 0 270)
			(unlocked yes)
			(layer "B.Fab")
			(hide yes)
			(effects
				(font
					(size 1 1)
					(thickness 0.15)
				)
				(justify mirror)
			)
		)
		(property "Author" "Antmicro"
			(at 0 0 270)
			(unlocked yes)
			(layer "B.Fab")
			(hide yes)
			(effects
				(font
					(size 1 1)
					(thickness 0.15)
				)
				(justify mirror)
			)
		)
		(sheetname "/TB Controller - Power/")
		(sheetfile "tb-power.kicad_sch")
		(attr smd)
		(fp_rect
			(start -0.925 0.47)
			(end 0.925 -0.47)
			(stroke
				(width 0.05)
				(type default)
			)
			(fill no)
			(layer "B.CrtYd")
		)
		(fp_rect
			(start -0.5 0.25)
			(end 0.5 -0.25)
			(stroke
				(width 0.15)
				(type solid)
			)
			(fill no)
			(layer "B.Fab")
		)
		(fp_text user "Author: Antmicro"
			(at -0.95 -4.169 90)
			(layer "B.Fab")
			(effects
				(font
					(size 0.7 0.7)
					(thickness 0.15)
				)
				(justify left bottom mirror)
			)
		)
		(fp_text user "License: Apache-2.0"
			(at -0.95 -5.169 90)
			(layer "B.Fab")
			(effects
				(font
					(size 0.7 0.7)
					(thickness 0.15)
				)
				(justify left bottom mirror)
			)
		)
		(fp_text user "${REFERENCE}"
			(at -0.95 -3.168 90)
			(layer "B.Fab")
			(effects
				(font
					(size 0.7 0.7)
					(thickness 0.15)
				)
				(justify left bottom mirror)
			)
		)
		(pad "1" smd roundrect
			(at -0.48 0 270)
			(size 0.59 0.64)
			(layers "B.Cu" "B.Mask" "B.Paste")
			(roundrect_rratio 0.25)
			(net 356 "/TB Controller - Power/0P9_BUFFERED")
			(pintype "passive")
		)
		(pad "2" smd roundrect
			(at 0.48 0 270)
			(size 0.59 0.64)
			(layers "B.Cu" "B.Mask" "B.Paste")
			(roundrect_rratio 0.25)
			(net 196 "Net-(Q1-B)")
			(pintype "passive")
		)
	)
	(footprint "antmicro-footprints:R_0402_1005Metric"
		(layer "B.Cu")
		(at 147.681866 92.485117 -90)
		(descr "Resistor SMD 0402")
		(tags "resistor SMD 0402")
		(property "Reference" "R150"
			(at 10.814884 -18.718134 90)
			(layer "B.SilkS")
			(effects
				(font
					(size 0.7 0.7)
					(thickness 0.15)
				)
				(justify mirror)
			)
		)
		(property "Value" "R_10k_0402"
			(at -1.011843 -1.772047 90)
			(layer "B.Fab")
			(effects
				(font
					(size 0.7 0.7)
					(thickness 0.15)
				)
				(justify left bottom mirror)
			)
		)
		(property "Datasheet" "https://www.bourns.com/docs/product-datasheets/cr.pdf"
			(at 0 0 90)
			(layer "B.Fab")
			(hide yes)
			(effects
				(font
					(size 1.27 1.27)
					(thickness 0.15)
				)
				(justify mirror)
			)
		)
		(property "Description" "SMD Chip Resistor, 10 kohm, ± 1%, 62.5 mW, 0402 [1005 Metric], Thick Film, General Purpose"
			(at 0 0 90)
			(layer "B.Fab")
			(hide yes)
			(effects
				(font
					(size 1.27 1.27)
					(thickness 0.15)
				)
				(justify mirror)
			)
		)
		(property "MPN" "CR0402-FX-1002GLF"
			(at 0 0 270)
			(unlocked yes)
			(layer "B.Fab")
			(hide yes)
			(effects
				(font
					(size 1 1)
					(thickness 0.15)
				)
				(justify mirror)
			)
		)
		(property "Manufacturer" "Bourns"
			(at 0 0 270)
			(unlocked yes)
			(layer "B.Fab")
			(hide yes)
			(effects
				(font
					(size 1 1)
					(thickness 0.15)
				)
				(justify mirror)
			)
		)
		(property "License" "Apache-2.0"
			(at 0 0 270)
			(unlocked yes)
			(layer "B.Fab")
			(hide yes)
			(effects
				(font
					(size 1 1)
					(thickness 0.15)
				)
				(justify mirror)
			)
		)
		(property "Author" "Antmicro"
			(at 0 0 270)
			(unlocked yes)
			(layer "B.Fab")
			(hide yes)
			(effects
				(font
					(size 1 1)
					(thickness 0.15)
				)
				(justify mirror)
			)
		)
		(property "Val" "10k"
			(at 0 0 270)
			(unlocked yes)
			(layer "B.Fab")
			(hide yes)
			(effects
				(font
					(size 1 1)
					(thickness 0.15)
				)
				(justify mirror)
			)
		)
		(property "Tolerance" "1%"
			(at 0 0 270)
			(unlocked yes)
			(layer "B.Fab")
			(hide yes)
			(effects
				(font
					(size 1 1)
					(thickness 0.15)
				)
				(justify mirror)
			)
		)
		(sheetname "/X710-AT2 Misc/")
		(sheetfile "x710-at2-mics.kicad_sch")
		(attr smd dnp)
		(fp_rect
			(start -0.925 0.47)
			(end 0.925 -0.47)
			(stroke
				(width 0.05)
				(type default)
			)
			(fill no)
			(layer "B.CrtYd")
		)
		(fp_rect
			(start -0.5 0.25)
			(end 0.5 -0.25)
			(stroke
				(width 0.15)
				(type solid)
			)
			(fill no)
			(layer "B.Fab")
		)
		(fp_text user "Author: Antmicro"
			(at -0.95 -4.169 90)
			(layer "B.Fab")
			(effects
				(font
					(size 0.7 0.7)
					(thickness 0.15)
				)
				(justify left bottom mirror)
			)
		)
		(fp_text user "${REFERENCE}"
			(at -0.95 -3.168 90)
			(layer "B.Fab")
			(effects
				(font
					(size 0.7 0.7)
					(thickness 0.15)
				)
				(justify left bottom mirror)
			)
		)
		(fp_text user "License: Apache-2.0"
			(at -0.95 -5.169 90)
			(layer "B.Fab")
			(effects
				(font
					(size 0.7 0.7)
					(thickness 0.15)
				)
				(justify left bottom mirror)
			)
		)
		(pad "1" smd roundrect
			(at -0.48 0 270)
			(size 0.59 0.64)
			(layers "B.Cu" "B.Mask" "B.Paste")
			(roundrect_rratio 0.25)
			(net 35 "/X710-AT2 Misc/POR_BYPASS")
			(pintype "passive")
		)
		(pad "2" smd roundrect
			(at 0.48 0 270)
			(size 0.59 0.64)
			(layers "B.Cu" "B.Mask" "B.Paste")
			(roundrect_rratio 0.25)
			(net 7 "+3V3")
			(pintype "passive")
		)
	)
	(footprint "antmicro-footprints:R_0402_1005Metric"
		(layer "B.Cu")
		(at 180.82 76)
		(descr "Resistor SMD 0402")
		(tags "resistor SMD 0402")
		(property "Reference" "R96"
			(at 3 0.4 180)
			(layer "B.SilkS")
			(effects
				(font
					(size 0.7 0.7)
					(thickness 0.15)
				)
				(justify left bottom mirror)
			)
		)
		(property "Value" "R_330R_0402"
			(at -1.011843 -1.772047 180)
			(layer "B.Fab")
			(effects
				(font
					(size 0.7 0.7)
					(thickness 0.15)
				)
				(justify left bottom mirror)
			)
		)
		(property "Datasheet" "https://www.bourns.com/docs/product-datasheets/cr.pdf"
			(at 0 0 180)
			(layer "B.Fab")
			(hide yes)
			(effects
				(font
					(size 1.27 1.27)
					(thickness 0.15)
				)
				(justify mirror)
			)
		)
		(property "Description" "SMD Chip Resistor, 330 ohm, ± 1%, 62.5 mW, 0402 [1005 Metric], Thick Film, General Purpose"
			(at 0 0 180)
			(layer "B.Fab")
			(hide yes)
			(effects
				(font
					(size 1.27 1.27)
					(thickness 0.15)
				)
				(justify mirror)
			)
		)
		(property "MPN" "CR0402-FX-3300GLF"
			(at 0 0 0)
			(unlocked yes)
			(layer "B.Fab")
			(hide yes)
			(effects
				(font
					(size 1 1)
					(thickness 0.15)
				)
				(justify mirror)
			)
		)
		(property "Manufacturer" "Bourns"
			(at 0 0 0)
			(unlocked yes)
			(layer "B.Fab")
			(hide yes)
			(effects
				(font
					(size 1 1)
					(thickness 0.15)
				)
				(justify mirror)
			)
		)
		(property "License" "Apache-2.0"
			(at 0 0 0)
			(unlocked yes)
			(layer "B.Fab")
			(hide yes)
			(effects
				(font
					(size 1 1)
					(thickness 0.15)
				)
				(justify mirror)
			)
		)
		(property "Author" "Antmicro"
			(at 0 0 0)
			(unlocked yes)
			(layer "B.Fab")
			(hide yes)
			(effects
				(font
					(size 1 1)
					(thickness 0.15)
				)
				(justify mirror)
			)
		)
		(property "Val" "330R"
			(at 0 0 0)
			(unlocked yes)
			(layer "B.Fab")
			(hide yes)
			(effects
				(font
					(size 1 1)
					(thickness 0.15)
				)
				(justify mirror)
			)
		)
		(property "Tolerance" "1%"
			(at 0 0 0)
			(unlocked yes)
			(layer "B.Fab")
			(hide yes)
			(effects
				(font
					(size 1 1)
					(thickness 0.15)
				)
				(justify mirror)
			)
		)
		(sheetname "/X710 DCDC converters/")
		(sheetfile "DCDC_converters_X710.kicad_sch")
		(attr smd)
		(fp_rect
			(start -0.925 0.47)
			(end 0.925 -0.47)
			(stroke
				(width 0.05)
				(type default)
			)
			(fill no)
			(layer "B.CrtYd")
		)
		(fp_rect
			(start -0.5 0.25)
			(end 0.5 -0.25)
			(stroke
				(width 0.15)
				(type solid)
			)
			(fill no)
			(layer "B.Fab")
		)
		(fp_text user "License: Apache-2.0"
			(at -0.95 -5.169 180)
			(layer "B.Fab")
			(effects
				(font
					(size 0.7 0.7)
					(thickness 0.15)
				)
				(justify left bottom mirror)
			)
		)
		(fp_text user "${REFERENCE}"
			(at -0.95 -3.168 180)
			(layer "B.Fab")
			(effects
				(font
					(size 0.7 0.7)
					(thickness 0.15)
				)
				(justify left bottom mirror)
			)
		)
		(fp_text user "Author: Antmicro"
			(at -0.95 -4.169 180)
			(layer "B.Fab")
			(effects
				(font
					(size 0.7 0.7)
					(thickness 0.15)
				)
				(justify left bottom mirror)
			)
		)
		(pad "1" smd roundrect
			(at -0.48 0)
			(size 0.59 0.64)
			(layers "B.Cu" "B.Mask" "B.Paste")
			(roundrect_rratio 0.25)
			(net 431 "Net-(Q5-C)")
			(pintype "passive")
		)
		(pad "2" smd roundrect
			(at 0.48 0)
			(size 0.59 0.64)
			(layers "B.Cu" "B.Mask" "B.Paste")
			(roundrect_rratio 0.25)
			(net 417 "Net-(D10-C)")
			(pintype "passive")
		)
	)
	(footprint "antmicro-footprints:C_0402_1005Metric"
		(layer "B.Cu")
		(at 129.474999 125.9 90)
		(descr "Capacitor SMD 0402")
		(tags "capacitor SMD 0402")
		(property "Reference" "C79"
			(at 7.700002 21.900002 270)
			(layer "B.SilkS")
			(effects
				(font
					(size 0.7 0.7)
					(thickness 0.15)
				)
				(justify mirror)
			)
		)
		(property "Value" "C_1u_0402"
			(at -1.022927 -2.155213 270)
			(layer "B.Fab")
			(effects
				(font
					(size 0.7 0.7)
					(thickness 0.15)
				)
				(justify left bottom mirror)
			)
		)
		(property "Datasheet" "https://product.tdk.com/en/search/capacitor/ceramic/mlcc/info?part_no=C1005X6S1A105K050BC"
			(at 0 0 270)
			(layer "B.Fab")
			(hide yes)
			(effects
				(font
					(size 1.27 1.27)
					(thickness 0.15)
				)
				(justify mirror)
			)
		)
		(property "Description" "SMD Multilayer Ceramic Capacitor, 1 µF, 10 V, 0402 [1005 Metric], ± 10%, X6S, C"
			(at 0 0 270)
			(layer "B.Fab")
			(hide yes)
			(effects
				(font
					(size 1.27 1.27)
					(thickness 0.15)
				)
				(justify mirror)
			)
		)
		(property "MPN" "C1005X6S1A105K050BC"
			(at 0 0 90)
			(unlocked yes)
			(layer "B.Fab")
			(hide yes)
			(effects
				(font
					(size 1 1)
					(thickness 0.15)
				)
				(justify mirror)
			)
		)
		(property "Manufacturer" "TDK"
			(at 0 0 90)
			(unlocked yes)
			(layer "B.Fab")
			(hide yes)
			(effects
				(font
					(size 1 1)
					(thickness 0.15)
				)
				(justify mirror)
			)
		)
		(property "License" "Apache-2.0"
			(at 0 0 90)
			(unlocked yes)
			(layer "B.Fab")
			(hide yes)
			(effects
				(font
					(size 1 1)
					(thickness 0.15)
				)
				(justify mirror)
			)
		)
		(property "Val" "1u"
			(at 0 0 90)
			(unlocked yes)
			(layer "B.Fab")
			(hide yes)
			(effects
				(font
					(size 1 1)
					(thickness 0.15)
				)
				(justify mirror)
			)
		)
		(property "Voltage" ""
			(at 0 0 90)
			(unlocked yes)
			(layer "B.Fab")
			(hide yes)
			(effects
				(font
					(size 1 1)
					(thickness 0.15)
				)
				(justify mirror)
			)
		)
		(property "Dielectric" ""
			(at 0 0 90)
			(unlocked yes)
			(layer "B.Fab")
			(hide yes)
			(effects
				(font
					(size 1 1)
					(thickness 0.15)
				)
				(justify mirror)
			)
		)
		(property "Author" "Antmicro"
			(at 0 0 90)
			(unlocked yes)
			(layer "B.Fab")
			(hide yes)
			(effects
				(font
					(size 1 1)
					(thickness 0.15)
				)
				(justify mirror)
			)
		)
		(sheetname "/TB Controller - Power/")
		(sheetfile "tb-power.kicad_sch")
		(attr smd)
		(fp_rect
			(start -0.925 0.47)
			(end 0.925 -0.47)
			(stroke
				(width 0.05)
				(type default)
			)
			(fill no)
			(layer "B.CrtYd")
		)
		(fp_line
			(start 0.504 -0.248)
			(end -0.494 -0.248)
			(stroke
				(width 0.15)
				(type solid)
			)
			(layer "B.Fab")
		)
		(fp_line
			(start -0.494 -0.248)
			(end -0.494 0.25)
			(stroke
				(width 0.15)
				(type solid)
			)
			(layer "B.Fab")
		)
		(fp_line
			(start 0.504 0.25)
			(end 0.504 -0.248)
			(stroke
				(width 0.15)
				(type solid)
			)
			(layer "B.Fab")
		)
		(fp_line
			(start -0.494 0.25)
			(end 0.504 0.25)
			(stroke
				(width 0.15)
				(type solid)
			)
			(layer "B.Fab")
		)
		(fp_text user "License: Apache-2.0"
			(at -0.939 -5.799 270)
			(layer "B.Fab")
			(effects
				(font
					(size 0.7 0.7)
					(thickness 0.15)
				)
				(justify left bottom mirror)
			)
		)
		(fp_text user "Author: Antmicro"
			(at -0.939 -3.399 270)
			(layer "B.Fab")
			(effects
				(font
					(size 0.7 0.7)
					(thickness 0.15)
				)
				(justify left bottom mirror)
			)
		)
		(fp_text user "${REFERENCE}"
			(at -0.939 -4.599 270)
			(layer "B.Fab")
			(effects
				(font
					(size 0.7 0.7)
					(thickness 0.15)
				)
				(justify left bottom mirror)
			)
		)
		(pad "1" smd roundrect
			(at -0.48 0 90)
			(size 0.59 0.64)
			(layers "B.Cu" "B.Mask" "B.Paste")
			(roundrect_rratio 0.25)
			(net 23 "GND")
			(pintype "passive")
		)
		(pad "2" smd roundrect
			(at 0.48 0 90)
			(size 0.59 0.64)
			(layers "B.Cu" "B.Mask" "B.Paste")
			(roundrect_rratio 0.25)
			(net 68 "/TB Controller - Power/VCC_0P9")
			(pintype "passive")
		)
	)
	(footprint "antmicro-footprints:C_0402_1005Metric"
		(layer "B.Cu")
		(at 154.261866 84.265117 180)
		(descr "Capacitor SMD 0402")
		(tags "capacitor SMD 0402")
		(property "Reference" "C189"
			(at -18.538135 -9.464883 0)
			(layer "B.SilkS")
			(effects
				(font
					(size 0.7 0.7)
					(thickness 0.15)
				)
				(justify mirror)
			)
		)
		(property "Value" "C_1u_25V_0402"
			(at -1.022927 -2.155213 0)
			(layer "B.Fab")
			(effects
				(font
					(size 0.7 0.7)
					(thickness 0.15)
				)
				(justify left bottom mirror)
			)
		)
		(property "Datasheet" "https://www.murata.com/products/productdetail?partno=GRM155R61E105KE11%23"
			(at 0 0 0)
			(layer "B.Fab")
			(hide yes)
			(effects
				(font
					(size 1.27 1.27)
					(thickness 0.15)
				)
				(justify mirror)
			)
		)
		(property "Description" "SMD Multilayer Ceramic Capacitor, 1 µF, 25 V, 0402 [1005 Metric], ± 10%, X5R, GRM Series"
			(at 0 0 0)
			(layer "B.Fab")
			(hide yes)
			(effects
				(font
					(size 1.27 1.27)
					(thickness 0.15)
				)
				(justify mirror)
			)
		)
		(property "MPN" "GRM155R61E105KE11J"
			(at 0 0 180)
			(unlocked yes)
			(layer "B.Fab")
			(hide yes)
			(effects
				(font
					(size 1 1)
					(thickness 0.15)
				)
				(justify mirror)
			)
		)
		(property "Manufacturer" "Murata"
			(at 0 0 180)
			(unlocked yes)
			(layer "B.Fab")
			(hide yes)
			(effects
				(font
					(size 1 1)
					(thickness 0.15)
				)
				(justify mirror)
			)
		)
		(property "License" "Apache-2.0"
			(at 0 0 180)
			(unlocked yes)
			(layer "B.Fab")
			(hide yes)
			(effects
				(font
					(size 1 1)
					(thickness 0.15)
				)
				(justify mirror)
			)
		)
		(property "Author" "Antmicro"
			(at 0 0 180)
			(unlocked yes)
			(layer "B.Fab")
			(hide yes)
			(effects
				(font
					(size 1 1)
					(thickness 0.15)
				)
				(justify mirror)
			)
		)
		(property "Val" "1u"
			(at 0 0 180)
			(unlocked yes)
			(layer "B.Fab")
			(hide yes)
			(effects
				(font
					(size 1 1)
					(thickness 0.15)
				)
				(justify mirror)
			)
		)
		(property "Voltage" "25V"
			(at 0 0 180)
			(unlocked yes)
			(layer "B.Fab")
			(hide yes)
			(effects
				(font
					(size 1 1)
					(thickness 0.15)
				)
				(justify mirror)
			)
		)
		(property "Dielectric" "X5R"
			(at 0 0 180)
			(unlocked yes)
			(layer "B.Fab")
			(hide yes)
			(effects
				(font
					(size 1 1)
					(thickness 0.15)
				)
				(justify mirror)
			)
		)
		(sheetname "/X710-AT2 power/")
		(sheetfile "x710-at2-power.kicad_sch")
		(attr smd)
		(fp_rect
			(start -0.925 0.47)
			(end 0.925 -0.47)
			(stroke
				(width 0.05)
				(type default)
			)
			(fill no)
			(layer "B.CrtYd")
		)
		(fp_line
			(start 0.504 0.25)
			(end 0.504 -0.248)
			(stroke
				(width 0.15)
				(type solid)
			)
			(layer "B.Fab")
		)
		(fp_line
			(start 0.504 -0.248)
			(end -0.494 -0.248)
			(stroke
				(width 0.15)
				(type solid)
			)
			(layer "B.Fab")
		)
		(fp_line
			(start -0.494 0.25)
			(end 0.504 0.25)
			(stroke
				(width 0.15)
				(type solid)
			)
			(layer "B.Fab")
		)
		(fp_line
			(start -0.494 -0.248)
			(end -0.494 0.25)
			(stroke
				(width 0.15)
				(type solid)
			)
			(layer "B.Fab")
		)
		(fp_text user "License: Apache-2.0"
			(at -0.939 -5.799 0)
			(layer "B.Fab")
			(effects
				(font
					(size 0.7 0.7)
					(thickness 0.15)
				)
				(justify left bottom mirror)
			)
		)
		(fp_text user "Author: Antmicro"
			(at -0.939 -3.399 0)
			(layer "B.Fab")
			(effects
				(font
					(size 0.7 0.7)
					(thickness 0.15)
				)
				(justify left bottom mirror)
			)
		)
		(fp_text user "${REFERENCE}"
			(at -0.939 -4.599 0)
			(layer "B.Fab")
			(effects
				(font
					(size 0.7 0.7)
					(thickness 0.15)
				)
				(justify left bottom mirror)
			)
		)
		(pad "1" smd roundrect
			(at -0.48 0 180)
			(size 0.59 0.64)
			(layers "B.Cu" "B.Mask" "B.Paste")
			(roundrect_rratio 0.25)
			(net 23 "GND")
			(pintype "passive")
		)
		(pad "2" smd roundrect
			(at 0.48 0 180)
			(size 0.59 0.64)
			(layers "B.Cu" "B.Mask" "B.Paste")
			(roundrect_rratio 0.25)
			(net 12 "XFI_VDD")
			(pintype "passive")
		)
	)
)
